(kicad_pcb
	(version 20240108)
	(generator "pcbnew")
	(generator_version "8.0")
	(general
		(thickness 1.62)
		(legacy_teardrops no)
	)
	(paper "A4")
	(title_block
		(title "Jetson Orin Baseboard")
		(date "2025-03-12")
		(rev "1.3.4")
		(company "Antmicro Ltd")
		(comment 1 "www.antmicro.com")
		(comment 9 "footprints 60-64 of 677")
	)
	(layers
		(0 "F.Cu" signal)
		(1 "In1.Cu" signal)
		(2 "In2.Cu" signal)
		(3 "In3.Cu" signal)
		(4 "In4.Cu" jumper)
		(5 "In5.Cu" signal)
		(6 "In6.Cu" signal)
		(31 "B.Cu" signal)
		(32 "B.Adhes" user "B.Adhesive")
		(33 "F.Adhes" user "F.Adhesive")
		(34 "B.Paste" user)
		(35 "F.Paste" user)
		(36 "B.SilkS" user "B.Silkscreen")
		(37 "F.SilkS" user "F.Silkscreen")
		(38 "B.Mask" user)
		(39 "F.Mask" user)
		(40 "Dwgs.User" user "User.Drawings")
		(41 "Cmts.User" user "User.Comments")
		(42 "Eco1.User" user "User.Eco1")
		(43 "Eco2.User" user "User.Eco2")
		(44 "Edge.Cuts" user)
		(45 "Margin" user)
		(46 "B.CrtYd" user "B.Courtyard")
		(47 "F.CrtYd" user "F.Courtyard")
		(48 "B.Fab" user)
		(49 "F.Fab" user)
	)
	(footprint "antmicro-footprints:SOT-523"
		(layer "F.Cu")
		(at 101.3 89.75 90)
		(property "Reference" "Q1"
			(at -0.325 -2.65 180)
			(layer "F.SilkS")
			(effects
				(font
					(size 0.7 0.7)
					(thickness 0.15)
				)
				(justify left bottom)
			)
		)
		(property "Value" "PJE138K"
			(at 0.1 1.824 90)
			(layer "F.Fab")
			(effects
				(font
					(size 0.7 0.7)
					(thickness 0.15)
				)
				(justify left bottom)
			)
		)
		(property "Footprint" "antmicro-footprints:SOT-523"
			(at 0 0 90)
			(layer "F.Fab")
			(hide yes)
			(effects
				(font
					(size 1.27 1.27)
					(thickness 0.15)
				)
			)
		)
		(property "Datasheet" "https://www.mouser.com/datasheet/2/1057/PJE138K-1876698.pdf"
			(at 0 0 90)
			(layer "F.Fab")
			(hide yes)
			(effects
				(font
					(size 1.27 1.27)
					(thickness 0.15)
				)
			)
		)
		(property "Author" "Antmicro"
			(at 191.05 -11.55 0)
			(layer "F.Fab")
			(hide yes)
			(effects
				(font
					(size 1 1)
					(thickness 0.15)
				)
			)
		)
		(property "License" "Apache-2.0"
			(at 191.05 -11.55 0)
			(layer "F.Fab")
			(hide yes)
			(effects
				(font
					(size 1 1)
					(thickness 0.15)
				)
			)
		)
		(property "MPN" "PJE138K_R1_00001"
			(at 191.05 -11.55 0)
			(layer "F.Fab")
			(hide yes)
			(effects
				(font
					(size 1 1)
					(thickness 0.15)
				)
			)
		)
		(property "Manufacturer" "PANJIT"
			(at 191.05 -11.55 0)
			(layer "F.Fab")
			(hide yes)
			(effects
				(font
					(size 1 1)
					(thickness 0.15)
				)
			)
		)
		(sheetname "HDMI")
		(sheetfile "hdmi.kicad_sch")
		(attr smd)
		(fp_line
			(start -0.277 -0.551)
			(end -0.277 -0.75)
			(stroke
				(width 0.15)
				(type solid)
			)
			(layer "F.SilkS")
		)
		(fp_line
			(start -0.725 -0.551)
			(end -0.277 -0.551)
			(stroke
				(width 0.15)
				(type solid)
			)
			(layer "F.SilkS")
		)
		(fp_line
			(start -0.927 -0.351)
			(end -0.725 -0.551)
			(stroke
				(width 0.15)
				(type solid)
			)
			(layer "F.SilkS")
		)
		(fp_line
			(start -0.927 -0.051)
			(end -0.927 -0.351)
			(stroke
				(width 0.15)
				(type solid)
			)
			(layer "F.SilkS")
		)
		(fp_circle
			(center -0.9652 0.9652)
			(end -0.9152 0.9652)
			(stroke
				(width 0.15)
				(type solid)
			)
			(fill solid)
			(layer "F.SilkS")
		)
		(fp_line
			(start 1.1 -1.16)
			(end 1.1 1.15)
			(stroke
				(width 0.05)
				(type solid)
			)
			(layer "F.CrtYd")
		)
		(fp_line
			(start -1.12 -1.16)
			(end 1.1 -1.16)
			(stroke
				(width 0.05)
				(type solid)
			)
			(layer "F.CrtYd")
		)
		(fp_line
			(start -1.12 -1.16)
			(end -1.12 1.15)
			(stroke
				(width 0.05)
				(type solid)
			)
			(layer "F.CrtYd")
		)
		(fp_line
			(start -1.12 1.15)
			(end 1.1 1.15)
			(stroke
				(width 0.05)
				(type solid)
			)
			(layer "F.CrtYd")
		)
		(fp_line
			(start 0.8 -0.425)
			(end -0.652 -0.425)
			(stroke
				(width 0.15)
				(type solid)
			)
			(layer "F.Fab")
		)
		(fp_line
			(start 0.8 -0.425)
			(end 0.8 0.424)
			(stroke
				(width 0.15)
				(type solid)
			)
			(layer "F.Fab")
		)
		(fp_line
			(start -0.652 -0.425)
			(end -0.802 -0.276)
			(stroke
				(width 0.15)
				(type solid)
			)
			(layer "F.Fab")
		)
		(fp_line
			(start -0.802 -0.276)
			(end -0.802 0.424)
			(stroke
				(width 0.15)
				(type solid)
			)
			(layer "F.Fab")
		)
		(fp_line
			(start 0.8 0.424)
			(end -0.802 0.424)
			(stroke
				(width 0.15)
				(type solid)
			)
			(layer "F.Fab")
		)
		(fp_circle
			(center -0.9652 0.9652)
			(end -0.9144 0.9652)
			(stroke
				(width 0.15)
				(type solid)
			)
			(fill none)
			(layer "F.Fab")
		)
		(fp_text user "License: Apache-2.0"
			(at -1.12 5.024 90)
			(layer "F.Fab")
			(hide yes)
			(effects
				(font
					(size 0.7 0.7)
					(thickness 0.15)
				)
				(justify left bottom)
			)
		)
		(fp_text user "${REFERENCE}"
			(at -1.12 3.824 90)
			(layer "F.Fab")
			(hide yes)
			(effects
				(font
					(size 0.7 0.7)
					(thickness 0.15)
				)
				(justify left bottom)
			)
		)
		(fp_text user "Author: Antmicro"
			(at -1.12 6.224 90)
			(layer "F.Fab")
			(hide yes)
			(effects
				(font
					(size 0.7 0.7)
					(thickness 0.15)
				)
				(justify left bottom)
			)
		)
		(pad "1" smd rect
			(at -0.5 0.65 90)
			(size 0.4 0.51)
			(layers "F.Cu" "F.Paste" "F.Mask")
			(net 112 "+1V8")
			(pinfunction "G")
			(pintype "passive")
		)
		(pad "2" smd rect
			(at 0.498 0.65 90)
			(size 0.4 0.51)
			(layers "F.Cu" "F.Paste" "F.Mask")
			(net 621 "Net-(Q1-S)")
			(pinfunction "S")
			(pintype "passive")
		)
		(pad "3" smd rect
			(at 0 -0.652 90)
			(size 0.4 0.51)
			(layers "F.Cu" "F.Paste" "F.Mask")
			(net 622 "Net-(Q1-D)")
			(pinfunction "D")
			(pintype "passive")
		)
	)
	(footprint "antmicro-footprints:XDFN-2_1x0.60mm"
		(layer "F.Cu")
		(at 137.8 84.15 -90)
		(property "Reference" "D48"
			(at 0.298 -0.402 180)
			(layer "F.SilkS")
			(effects
				(font
					(size 0.7 0.7)
					(thickness 0.15)
				)
				(justify left bottom)
			)
		)
		(property "Value" "TPD1E0B04_XDFN-2"
			(at 0 1.5 -90)
			(layer "F.Fab")
			(effects
				(font
					(size 0.7 0.7)
					(thickness 0.15)
				)
				(justify left bottom)
			)
		)
		(property "Footprint" "antmicro-footprints:XDFN-2_1x0.60mm"
			(at 0 0 -90)
			(layer "F.Fab")
			(hide yes)
			(effects
				(font
					(size 1.27 1.27)
					(thickness 0.15)
				)
			)
		)
		(property "Datasheet" "https://www.ti.com/general/docs/suppproductinfo.tsp?distId=26&gotoUrl=https://www.ti.com/lit/gpn/tpd1e0b04"
			(at 0 0 -90)
			(layer "F.Fab")
			(hide yes)
			(effects
				(font
					(size 1.27 1.27)
					(thickness 0.15)
				)
			)
		)
		(property "MPN" "TPD1E0B04DPYR"
			(at 53.65 221.95 0)
			(layer "F.Fab")
			(hide yes)
			(effects
				(font
					(size 1 1)
					(thickness 0.15)
				)
			)
		)
		(property "Manufacturer" "Texas Instruments"
			(at 53.65 221.95 0)
			(layer "F.Fab")
			(hide yes)
			(effects
				(font
					(size 1 1)
					(thickness 0.15)
				)
			)
		)
		(property "Author" "Antmicro"
			(at 53.65 221.95 0)
			(layer "F.Fab")
			(hide yes)
			(effects
				(font
					(size 1 1)
					(thickness 0.15)
				)
			)
		)
		(property "License" "Apache-2.0"
			(at 53.65 221.95 0)
			(layer "F.Fab")
			(hide yes)
			(effects
				(font
					(size 1 1)
					(thickness 0.15)
				)
			)
		)
		(sheetname "Peripherals")
		(sheetfile "peripherals.kicad_sch")
		(attr smd)
		(fp_rect
			(start -0.725 -0.475)
			(end 0.725 0.475)
			(stroke
				(width 0.05)
				(type solid)
			)
			(fill none)
			(layer "F.CrtYd")
		)
		(fp_rect
			(start -0.55 -0.35)
			(end 0.55 0.35)
			(stroke
				(width 0.15)
				(type solid)
			)
			(fill none)
			(layer "F.Fab")
		)
		(fp_text user "${REFERENCE}"
			(at -0.8 3.2 -90)
			(layer "F.Fab")
			(hide yes)
			(effects
				(font
					(size 0.7 0.7)
					(thickness 0.15)
				)
				(justify left bottom)
			)
		)
		(fp_text user "License: Apache-2.0"
			(at -0.8 5.6 -90)
			(layer "F.Fab")
			(hide yes)
			(effects
				(font
					(size 0.7 0.7)
					(thickness 0.15)
				)
				(justify left bottom)
			)
		)
		(fp_text user "Author: Antmicro"
			(at -0.8 4.4 -90)
			(layer "F.Fab")
			(hide yes)
			(effects
				(font
					(size 0.7 0.7)
					(thickness 0.15)
				)
				(justify left bottom)
			)
		)
		(pad "1" smd roundrect
			(at -0.351 0 270)
			(size 0.3 0.5)
			(layers "F.Cu" "F.Paste" "F.Mask")
			(roundrect_rratio 0.25)
			(net 413 "/Peripherals/PCIE2_TX1_CONN_P")
			(pinfunction "C")
			(pintype "passive")
		)
		(pad "2" smd roundrect
			(at 0.349 0 270)
			(size 0.3 0.5)
			(layers "F.Cu" "F.Paste" "F.Mask")
			(roundrect_rratio 0.25)
			(net 1 "GND")
			(pinfunction "A")
			(pintype "passive")
		)
	)
	(footprint "antmicro-footprints:R_0402_1005Metric"
		(layer "F.Cu")
		(at 101.35 91.4)
		(descr "Resistor SMD 0402")
		(tags "resistor SMD 0402")
		(property "Reference" "R49"
			(at -1.05 1.35 0)
			(layer "F.SilkS")
			(effects
				(font
					(size 0.7 0.7)
					(thickness 0.15)
				)
				(justify left bottom)
			)
		)
		(property "Value" "R_10k_0402"
			(at 0 1.4 0)
			(layer "F.Fab")
			(effects
				(font
					(size 0.7 0.7)
					(thickness 0.15)
				)
				(justify left bottom)
			)
		)
		(property "Footprint" "antmicro-footprints:R_0402_1005Metric"
			(at 0 0 0)
			(layer "F.Fab")
			(hide yes)
			(effects
				(font
					(size 1.27 1.27)
					(thickness 0.15)
				)
			)
		)
		(property "Datasheet" "https://www.bourns.com/docs/product-datasheets/cr.pdf"
			(at 0 0 0)
			(layer "F.Fab")
			(hide yes)
			(effects
				(font
					(size 1.27 1.27)
					(thickness 0.15)
				)
			)
		)
		(property "Author" "Antmicro"
			(at 0 0 0)
			(layer "F.Fab")
			(hide yes)
			(effects
				(font
					(size 1 1)
					(thickness 0.15)
				)
			)
		)
		(property "License" "Apache-2.0"
			(at 0 0 0)
			(layer "F.Fab")
			(hide yes)
			(effects
				(font
					(size 1 1)
					(thickness 0.15)
				)
			)
		)
		(property "MPN" "CR0402-FX-1002GLF"
			(at 0 0 0)
			(layer "F.Fab")
			(hide yes)
			(effects
				(font
					(size 1 1)
					(thickness 0.15)
				)
			)
		)
		(property "Manufacturer" "Bourns"
			(at 0 0 0)
			(layer "F.Fab")
			(hide yes)
			(effects
				(font
					(size 1 1)
					(thickness 0.15)
				)
			)
		)
		(property "Tolerance" "1%"
			(at 0 0 0)
			(layer "F.Fab")
			(hide yes)
			(effects
				(font
					(size 1 1)
					(thickness 0.15)
				)
			)
		)
		(property "Val" "10k"
			(at 0 0 0)
			(layer "F.Fab")
			(hide yes)
			(effects
				(font
					(size 1 1)
					(thickness 0.15)
				)
			)
		)
		(sheetname "HDMI")
		(sheetfile "hdmi.kicad_sch")
		(attr smd)
		(fp_rect
			(start -0.925 -0.47)
			(end 0.925 0.47)
			(stroke
				(width 0.05)
				(type default)
			)
			(fill none)
			(layer "F.CrtYd")
		)
		(fp_rect
			(start -0.5 -0.25)
			(end 0.5 0.25)
			(stroke
				(width 0.15)
				(type solid)
			)
			(fill none)
			(layer "F.Fab")
		)
		(fp_text user "License: Apache-2.0"
			(at -0.95 5.169 0)
			(layer "F.Fab")
			(hide yes)
			(effects
				(font
					(size 0.7 0.7)
					(thickness 0.15)
				)
				(justify left bottom)
			)
		)
		(fp_text user "Author: Antmicro"
			(at -0.95 4.169 0)
			(layer "F.Fab")
			(hide yes)
			(effects
				(font
					(size 0.7 0.7)
					(thickness 0.15)
				)
				(justify left bottom)
			)
		)
		(fp_text user "${REFERENCE}"
			(at -0.95 3.168 0)
			(layer "F.Fab")
			(hide yes)
			(effects
				(font
					(size 0.7 0.7)
					(thickness 0.15)
				)
				(justify left bottom)
			)
		)
		(pad "1" smd roundrect
			(at -0.48 0)
			(size 0.59 0.64)
			(layers "F.Cu" "F.Paste" "F.Mask")
			(roundrect_rratio 0.25)
			(net 622 "Net-(Q1-D)")
			(pintype "passive")
		)
		(pad "2" smd roundrect
			(at 0.48 0)
			(size 0.59 0.64)
			(layers "F.Cu" "F.Paste" "F.Mask")
			(roundrect_rratio 0.25)
			(net 87 "+3V3")
			(pintype "passive")
		)
	)
	(footprint "antmicro-footprints:TP_SMD_0.75mm"
		(layer "F.Cu")
		(at 96.95 83.1 180)
		(property "Reference" "TP5"
			(at -0.25 -0.4 180)
			(layer "F.SilkS")
			(effects
				(font
					(size 0.7 0.7)
					(thickness 0.15)
				)
				(justify left bottom)
			)
		)
		(property "Value" "TP_0.75mm_SMD"
			(at 0 1.2 180)
			(layer "F.Fab")
			(effects
				(font
					(size 0.7 0.7)
					(thickness 0.15)
				)
				(justify left bottom)
			)
		)
		(property "Footprint" "antmicro-footprints:TP_SMD_0.75mm"
			(at 0 0 180)
			(layer "F.Fab")
			(hide yes)
			(effects
				(font
					(size 1.27 1.27)
					(thickness 0.15)
				)
			)
		)
		(property "Author" "Antmicro"
			(at 193.9 166.2 0)
			(layer "F.Fab")
			(hide yes)
			(effects
				(font
					(size 1 1)
					(thickness 0.15)
				)
			)
		)
		(property "License" "Apache-2.0"
			(at 193.9 166.2 0)
			(layer "F.Fab")
			(hide yes)
			(effects
				(font
					(size 1 1)
					(thickness 0.15)
				)
			)
		)
		(property "MPN" ""
			(at 193.9 166.2 0)
			(layer "F.Fab")
			(hide yes)
			(effects
				(font
					(size 1 1)
					(thickness 0.15)
				)
			)
		)
		(property "Manufacturer" ""
			(at 193.9 166.2 0)
			(layer "F.Fab")
			(hide yes)
			(effects
				(font
					(size 1 1)
					(thickness 0.15)
				)
			)
		)
		(sheetname "SoM")
		(sheetfile "som.kicad_sch")
		(attr exclude_from_pos_files exclude_from_bom)
		(fp_circle
			(center 0 0)
			(end 0.475 0)
			(stroke
				(width 0.05)
				(type default)
			)
			(fill none)
			(layer "F.CrtYd")
		)
		(fp_text user "${REFERENCE}"
			(at -0.4 2.7 180)
			(layer "F.Fab")
			(hide yes)
			(effects
				(font
					(size 0.7 0.7)
					(thickness 0.15)
				)
				(justify left bottom)
			)
		)
		(fp_text user "Author: Antmicro"
			(at -0.4 3.901 180)
			(layer "F.Fab")
			(hide yes)
			(effects
				(font
					(size 0.7 0.7)
					(thickness 0.15)
				)
				(justify left bottom)
			)
		)
		(fp_text user "License: Apache-2.0"
			(at -0.4 5.101 180)
			(layer "F.Fab")
			(hide yes)
			(effects
				(font
					(size 0.7 0.7)
					(thickness 0.15)
				)
				(justify left bottom)
			)
		)
		(pad "1" smd circle
			(at 0 0 180)
			(size 0.75 0.75)
			(layers "F.Cu" "F.Mask")
			(net 744 "Net-(J15B-CAM0_MCLK)")
			(pinfunction "1")
			(pintype "passive")
		)
	)
	(footprint "antmicro-footprints:R_0402_1005Metric"
		(layer "F.Cu")
		(at 65.91 94.35)
		(descr "Resistor SMD 0402")
		(tags "resistor SMD 0402")
		(property "Reference" "R237"
			(at -1.12 -1.46 0)
			(layer "F.SilkS")
			(effects
				(font
					(size 0.7 0.7)
					(thickness 0.15)
				)
				(justify left bottom)
			)
		)
		(property "Value" "R_499k_0402"
			(at -1.011843 1.772047 0)
			(layer "F.Fab")
			(effects
				(font
					(size 0.7 0.7)
					(thickness 0.15)
				)
				(justify left bottom)
			)
		)
		(property "Footprint" "antmicro-footprints:R_0402_1005Metric"
			(at 0 0 0)
			(layer "F.Fab")
			(hide yes)
			(effects
				(font
					(size 1.27 1.27)
					(thickness 0.15)
				)
			)
		)
		(property "Datasheet" "https://www.mouser.com/datasheet/2/54/cr-1858361.pdf"
			(at 0 0 0)
			(layer "F.Fab")
			(hide yes)
			(effects
				(font
					(size 1.27 1.27)
					(thickness 0.15)
				)
			)
		)
		(property "Author" "Antmicro"
			(at 0 0 0)
			(layer "F.Fab")
			(hide yes)
			(effects
				(font
					(size 1 1)
					(thickness 0.15)
				)
			)
		)
		(property "License" "Apache-2.0"
			(at 0 0 0)
			(layer "F.Fab")
			(hide yes)
			(effects
				(font
					(size 1 1)
					(thickness 0.15)
				)
			)
		)
		(property "MPN" "CR0402-FX-4993GLF"
			(at 0 0 0)
			(layer "F.Fab")
			(hide yes)
			(effects
				(font
					(size 1 1)
					(thickness 0.15)
				)
			)
		)
		(property "Manufacturer" "Bourns"
			(at 0 0 0)
			(layer "F.Fab")
			(hide yes)
			(effects
				(font
					(size 1 1)
					(thickness 0.15)
				)
			)
		)
		(property "Tolerance" "1%"
			(at 0 0 0)
			(layer "F.Fab")
			(hide yes)
			(effects
				(font
					(size 1 1)
					(thickness 0.15)
				)
			)
		)
		(property "Val" "499k"
			(at 0 0 0)
			(layer "F.Fab")
			(hide yes)
			(effects
				(font
					(size 1 1)
					(thickness 0.15)
				)
			)
		)
		(sheetname "Supply")
		(sheetfile "supply.kicad_sch")
		(attr smd)
		(fp_rect
			(start -0.925 -0.47)
			(end 0.925 0.47)
			(stroke
				(width 0.05)
				(type default)
			)
			(fill none)
			(layer "F.CrtYd")
		)
		(fp_rect
			(start -0.5 -0.25)
			(end 0.5 0.25)
			(stroke
				(width 0.15)
				(type solid)
			)
			(fill none)
			(layer "F.Fab")
		)
		(fp_text user "${REFERENCE}"
			(at -0.95 3.168 0)
			(layer "F.Fab")
			(hide yes)
			(effects
				(font
					(size 0.7 0.7)
					(thickness 0.15)
				)
				(justify left bottom)
			)
		)
		(fp_text user "License: Apache-2.0"
			(at -0.95 5.169 0)
			(layer "F.Fab")
			(hide yes)
			(effects
				(font
					(size 0.7 0.7)
					(thickness 0.15)
				)
				(justify left bottom)
			)
		)
		(fp_text user "Author: Antmicro"
			(at -0.95 4.169 0)
			(layer "F.Fab")
			(hide yes)
			(effects
				(font
					(size 0.7 0.7)
					(thickness 0.15)
				)
				(justify left bottom)
			)
		)
		(pad "1" smd roundrect
			(at -0.48 0)
			(size 0.59 0.64)
			(layers "F.Cu" "F.Paste" "F.Mask")
			(roundrect_rratio 0.25)
			(net 1 "GND")
			(pintype "passive")
		)
		(pad "2" smd roundrect
			(at 0.48 0)
			(size 0.59 0.64)
			(layers "F.Cu" "F.Paste" "F.Mask")
			(roundrect_rratio 0.25)
			(net 764 "/Supply/5V_MODE1")
			(pintype "passive")
		)
	)
)
